(kicad_pcb
	(version 20260206)
	(generator "pcbnew")
	(generator_version "10.0")
	(general
		(thickness 1.6)
		(legacy_teardrops no)
	)
	(paper "A4")
	(title_block
		(title "panther-plus-userver — 13130-1b_20150205.brd")
		(comment 1 "Honey Badger (Wiwynn) / footprint 894 of 1509 (DIMM1), pads 163-169 of 210")
	)
	(layers
		(0 "F.Cu" signal "TOP")
		(4 "In1.Cu" signal "L2")
		(6 "In2.Cu" signal "L3")
		(8 "In3.Cu" signal "L4")
		(10 "In4.Cu" signal "L5")
		(12 "In5.Cu" signal "L6")
		(14 "In6.Cu" signal "L7")
		(16 "In7.Cu" signal "L8")
		(18 "In8.Cu" signal "L9")
		(20 "In9.Cu" signal "L10")
		(22 "In10.Cu" signal "L11")
		(2 "B.Cu" signal "BOTTOM")
		(9 "F.Adhes" user "F.Adhesive")
		(11 "B.Adhes" user "B.Adhesive")
		(13 "F.Paste" user "Package Geometry/Pastemask Top")
		(15 "B.Paste" user "Package Geometry/Pastemask Bottom")
		(5 "F.SilkS" user "Ref Des/Silkscreen Top")
		(7 "B.SilkS" user "Ref Des/Silkscreen Bottom")
		(1 "F.Mask" user "Board Geometry/Soldermask Top")
		(3 "B.Mask" user "Board Geometry/Soldermask Bottom")
		(17 "Dwgs.User" user "User.Drawings")
		(19 "Cmts.User" user "User.Comments")
		(21 "Eco1.User" user "User.Eco1")
		(23 "Eco2.User" user "User.Eco2")
		(25 "Edge.Cuts" user "Board Geometry/Outline")
		(27 "Margin" user)
		(31 "F.CrtYd" user "Package Geometry/Place Bound Top")
		(29 "B.CrtYd" user "Package Geometry/Place Bound Bottom")
		(35 "F.Fab" user "Ref Des/Assembly Top")
		(33 "B.Fab" user "Ref Des/Assembly Bottom")
	)
	(footprint ""
		(layer "B.Cu")
		(at 158.500064 -66.699892 180)
		(property "Reference" "DIMM1"
			(at 0 0 0)
			(layer "B.SilkS")
			(hide yes)
			(effects
				(font
					(size 1.27 1.27)
				)
				(justify mirror)
			)
		)
		(property "Value" "DDR3-204P-142-COLAY-1-GP-U"
			(at 41.312338 -16.676878 180)
			(unlocked yes)
			(layer "B.Fab")
			(hide yes)
			(effects
				(font
					(size 1.016 1.016)
					(thickness 0.1524)
				)
				(justify mirror)
			)
		)
		(property "Device Type" "AS0A626-J8R6-7H-COLAY-1"
			(at 41.312338 -18.200878 180)
			(unlocked yes)
			(layer "B.Fab")
			(hide yes)
			(effects
				(font
					(size 1.016 1.016)
					(thickness 0.1524)
				)
				(justify mirror)
			)
		)
		(duplicate_pad_numbers_are_jumpers no)
		(pad "161" smd custom
			(at 18.750026 -4.100068)
			(size 0.1143 0.1143)
			(layers "B.Cu" "B.Mask" "B.Paste")
			(net "M_A_DQ43")
			(options
				(clearance outline)
				(anchor circle)
			)
			(primitives
				(gr_poly
					(pts
						(xy 0 -0.9017) (xy -0.03175 -0.89916) (xy -0.0635 -0.889) (xy -0.09144 -0.87376) (xy -0.11684 -0.85344)
						(xy -0.13716 -0.82804) (xy -0.1524 -0.8001) (xy -0.16256 -0.76835) (xy -0.1651 -0.7366) (xy -0.1651 -0.44958)
						(xy -0.17272 -0.44196) (xy -0.19812 -0.4064) (xy -0.2032 -0.39624) (xy -0.20701 -0.38735) (xy -0.21209 -0.37719)
						(xy -0.2159 -0.36703) (xy -0.21844 -0.35687) (xy -0.22225 -0.34544) (xy -0.22352 -0.33528) (xy -0.22606 -0.32512)
						(xy -0.22733 -0.31369) (xy -0.22733 -0.30353) (xy -0.2286 -0.2921) (xy -0.22733 -0.28067) (xy -0.22733 -0.27051)
						(xy -0.22606 -0.25908) (xy -0.22352 -0.24892) (xy -0.22225 -0.23876) (xy -0.21844 -0.22733) (xy -0.2159 -0.21717)
						(xy -0.21209 -0.20701) (xy -0.20701 -0.19685) (xy -0.2032 -0.18796) (xy -0.19812 -0.1778) (xy -0.17272 -0.14224)
						(xy -0.1651 -0.13462) (xy -0.1651 0.7366) (xy -0.16256 0.76835) (xy -0.1524 0.8001) (xy -0.13716 0.82804)
						(xy -0.11684 0.85344) (xy -0.09144 0.87376) (xy -0.0635 0.889) (xy -0.03175 0.89916) (xy 0 0.9017)
						(xy 0.03175 0.89916) (xy 0.0635 0.889) (xy 0.09144 0.87376) (xy 0.11684 0.85344) (xy 0.13716 0.82804)
						(xy 0.1524 0.8001) (xy 0.16256 0.76835) (xy 0.1651 0.7366) (xy 0.1651 -0.13462) (xy 0.17272 -0.14224)
						(xy 0.19812 -0.1778) (xy 0.2032 -0.18796) (xy 0.20701 -0.19685) (xy 0.21209 -0.20701) (xy 0.2159 -0.21717)
						(xy 0.21844 -0.22733) (xy 0.22225 -0.23876) (xy 0.22352 -0.24892) (xy 0.22606 -0.25908) (xy 0.22733 -0.27051)
						(xy 0.22733 -0.28067) (xy 0.2286 -0.2921) (xy 0.22733 -0.30353) (xy 0.22733 -0.31369) (xy 0.22606 -0.32512)
						(xy 0.22352 -0.33528) (xy 0.22225 -0.34544) (xy 0.21844 -0.35687) (xy 0.2159 -0.36703) (xy 0.21209 -0.37719)
						(xy 0.20701 -0.38735) (xy 0.2032 -0.39624) (xy 0.19812 -0.4064) (xy 0.17272 -0.44196) (xy 0.1651 -0.44958)
						(xy 0.1651 -0.7366) (xy 0.16256 -0.76835) (xy 0.1524 -0.8001) (xy 0.13716 -0.82804) (xy 0.11684 -0.85344)
						(xy 0.09144 -0.87376) (xy 0.0635 -0.889) (xy 0.03175 -0.89916)
					)
					(width 0)
					(fill yes)
				)
			)
		)
		(pad "162" smd custom
			(at 19.05 4.100068)
			(size 0.1143 0.1143)
			(layers "B.Cu" "B.Mask" "B.Paste")
			(net "M_A_DQ47")
			(options
				(clearance outline)
				(anchor circle)
			)
			(primitives
				(gr_poly
					(pts
						(xy 0 -0.9017) (xy -0.03175 -0.89916) (xy -0.0635 -0.889) (xy -0.09144 -0.87376) (xy -0.11684 -0.85344)
						(xy -0.13716 -0.82804) (xy -0.1524 -0.8001) (xy -0.16256 -0.76835) (xy -0.1651 -0.7366) (xy -0.1651 0.13462)
						(xy -0.17272 0.14224) (xy -0.19812 0.1778) (xy -0.2032 0.18796) (xy -0.20701 0.19685) (xy -0.21209 0.20701)
						(xy -0.2159 0.21717) (xy -0.21844 0.22733) (xy -0.22225 0.23876) (xy -0.22352 0.24892) (xy -0.22606 0.25908)
						(xy -0.22733 0.27051) (xy -0.22733 0.28067) (xy -0.2286 0.2921) (xy -0.22733 0.30353) (xy -0.22733 0.31369)
						(xy -0.22606 0.32512) (xy -0.22352 0.33528) (xy -0.22225 0.34544) (xy -0.21844 0.35687) (xy -0.2159 0.36703)
						(xy -0.21209 0.37719) (xy -0.20701 0.38735) (xy -0.2032 0.39624) (xy -0.19812 0.4064) (xy -0.17272 0.44196)
						(xy -0.1651 0.44958) (xy -0.1651 0.7366) (xy -0.16256 0.76835) (xy -0.1524 0.8001) (xy -0.13716 0.82804)
						(xy -0.11684 0.85344) (xy -0.09144 0.87376) (xy -0.0635 0.889) (xy -0.03175 0.89916) (xy 0 0.9017)
						(xy 0.03175 0.89916) (xy 0.0635 0.889) (xy 0.09144 0.87376) (xy 0.11684 0.85344) (xy 0.13716 0.82804)
						(xy 0.1524 0.8001) (xy 0.16256 0.76835) (xy 0.1651 0.7366) (xy 0.1651 0.44958) (xy 0.17272 0.44196)
						(xy 0.19812 0.4064) (xy 0.2032 0.39624) (xy 0.20701 0.38735) (xy 0.21209 0.37719) (xy 0.2159 0.36703)
						(xy 0.21844 0.35687) (xy 0.22225 0.34544) (xy 0.22352 0.33528) (xy 0.22606 0.32512) (xy 0.22733 0.31369)
						(xy 0.22733 0.30353) (xy 0.2286 0.2921) (xy 0.22733 0.28067) (xy 0.22733 0.27051) (xy 0.22606 0.25908)
						(xy 0.22352 0.24892) (xy 0.22225 0.23876) (xy 0.21844 0.22733) (xy 0.2159 0.21717) (xy 0.21209 0.20701)
						(xy 0.20701 0.19685) (xy 0.2032 0.18796) (xy 0.19812 0.1778) (xy 0.17272 0.14224) (xy 0.1651 0.13462)
						(xy 0.1651 -0.7366) (xy 0.16256 -0.76835) (xy 0.1524 -0.8001) (xy 0.13716 -0.82804) (xy 0.11684 -0.85344)
						(xy 0.09144 -0.87376) (xy 0.0635 -0.889) (xy 0.03175 -0.89916)
					)
					(width 0)
					(fill yes)
				)
			)
		)
		(pad "163" smd custom
			(at 19.349974 -4.100068)
			(size 0.1143 0.1143)
			(layers "B.Cu" "B.Mask" "B.Paste")
			(net "GND")
			(options
				(clearance outline)
				(anchor circle)
			)
			(primitives
				(gr_poly
					(pts
						(xy 0 -0.9017) (xy -0.03175 -0.89916) (xy -0.0635 -0.889) (xy -0.09144 -0.87376) (xy -0.11684 -0.85344)
						(xy -0.13716 -0.82804) (xy -0.1524 -0.8001) (xy -0.16256 -0.76835) (xy -0.1651 -0.7366) (xy -0.1651 -0.19685)
						(xy -0.17272 -0.18923) (xy -0.17907 -0.18034) (xy -0.18669 -0.17145) (xy -0.19177 -0.16256) (xy -0.19812 -0.15367)
						(xy -0.20828 -0.13335) (xy -0.21971 -0.10287) (xy -0.22225 -0.09271) (xy -0.22479 -0.08128) (xy -0.22606 -0.07112)
						(xy -0.2286 -0.05969) (xy -0.2286 -0.01651) (xy -0.22606 -0.00508) (xy -0.22479 0.00508) (xy -0.22225 0.01651)
						(xy -0.21971 0.02667) (xy -0.20828 0.05715) (xy -0.19812 0.07747) (xy -0.19177 0.08636) (xy -0.18669 0.09525)
						(xy -0.17907 0.10414) (xy -0.17272 0.11303) (xy -0.1651 0.12065) (xy -0.1651 0.7366) (xy -0.16256 0.76835)
						(xy -0.1524 0.8001) (xy -0.13716 0.82804) (xy -0.11684 0.85344) (xy -0.09144 0.87376) (xy -0.0635 0.889)
						(xy -0.03175 0.89916) (xy 0 0.9017) (xy 0.03175 0.89916) (xy 0.0635 0.889) (xy 0.09144 0.87376)
						(xy 0.11684 0.85344) (xy 0.13716 0.82804) (xy 0.1524 0.8001) (xy 0.16256 0.76835) (xy 0.1651 0.7366)
						(xy 0.1651 0.11938) (xy 0.17272 0.11176) (xy 0.19812 0.0762) (xy 0.2032 0.06604) (xy 0.20701 0.05715)
						(xy 0.21209 0.04699) (xy 0.2159 0.03683) (xy 0.21844 0.02667) (xy 0.22225 0.01524) (xy 0.22352 0.00508)
						(xy 0.22606 -0.00508) (xy 0.22733 -0.01651) (xy 0.22733 -0.02667) (xy 0.2286 -0.0381) (xy 0.22733 -0.04953)
						(xy 0.22733 -0.05969) (xy 0.22606 -0.07112) (xy 0.22352 -0.08128) (xy 0.22225 -0.09144) (xy 0.21844 -0.10287)
						(xy 0.2159 -0.11303) (xy 0.21209 -0.12319) (xy 0.20701 -0.13335) (xy 0.2032 -0.14224) (xy 0.19812 -0.1524)
						(xy 0.17272 -0.18796) (xy 0.1651 -0.19558) (xy 0.1651 -0.7366) (xy 0.16256 -0.76835) (xy 0.1524 -0.8001)
						(xy 0.13716 -0.82804) (xy 0.11684 -0.85344) (xy 0.09144 -0.87376) (xy 0.0635 -0.889) (xy 0.03175 -0.89916)
					)
					(width 0)
					(fill yes)
				)
			)
		)
		(pad "164" smd custom
			(at 19.649948 4.100068)
			(size 0.1143 0.1143)
			(layers "B.Cu" "B.Mask" "B.Paste")
			(net "GND")
			(options
				(clearance outline)
				(anchor circle)
			)
			(primitives
				(gr_poly
					(pts
						(xy 0 -0.9017) (xy -0.03175 -0.89916) (xy -0.0635 -0.889) (xy -0.09144 -0.87376) (xy -0.11684 -0.85344)
						(xy -0.13716 -0.82804) (xy -0.1524 -0.8001) (xy -0.16256 -0.76835) (xy -0.1651 -0.7366) (xy -0.1651 -0.11938)
						(xy -0.17272 -0.11176) (xy -0.19812 -0.0762) (xy -0.2032 -0.06604) (xy -0.20701 -0.05715) (xy -0.21209 -0.04699)
						(xy -0.2159 -0.03683) (xy -0.21844 -0.02667) (xy -0.22225 -0.01524) (xy -0.22352 -0.00508) (xy -0.22606 0.00508)
						(xy -0.22733 0.01651) (xy -0.22733 0.02667) (xy -0.2286 0.0381) (xy -0.22733 0.04953) (xy -0.22733 0.05969)
						(xy -0.22606 0.07112) (xy -0.22352 0.08128) (xy -0.22225 0.09144) (xy -0.21844 0.10287) (xy -0.2159 0.11303)
						(xy -0.21209 0.12319) (xy -0.20701 0.13335) (xy -0.2032 0.14224) (xy -0.19812 0.1524) (xy -0.17272 0.18796)
						(xy -0.1651 0.19558) (xy -0.1651 0.7366) (xy -0.16256 0.76835) (xy -0.1524 0.8001) (xy -0.13716 0.82804)
						(xy -0.11684 0.85344) (xy -0.09144 0.87376) (xy -0.0635 0.889) (xy -0.03175 0.89916) (xy 0 0.9017)
						(xy 0.03175 0.89916) (xy 0.0635 0.889) (xy 0.09144 0.87376) (xy 0.11684 0.85344) (xy 0.13716 0.82804)
						(xy 0.1524 0.8001) (xy 0.16256 0.76835) (xy 0.1651 0.7366) (xy 0.1651 0.19685) (xy 0.17272 0.18923)
						(xy 0.17907 0.18034) (xy 0.18669 0.17145) (xy 0.19177 0.16256) (xy 0.19812 0.15367) (xy 0.20828 0.13335)
						(xy 0.21971 0.10287) (xy 0.22225 0.09271) (xy 0.22479 0.08128) (xy 0.22606 0.07112) (xy 0.2286 0.05969)
						(xy 0.2286 0.01651) (xy 0.22606 0.00508) (xy 0.22479 -0.00508) (xy 0.22225 -0.01651) (xy 0.21971 -0.02667)
						(xy 0.20828 -0.05715) (xy 0.19812 -0.07747) (xy 0.19177 -0.08636) (xy 0.18669 -0.09525) (xy 0.17907 -0.10414)
						(xy 0.17272 -0.11303) (xy 0.1651 -0.12065) (xy 0.1651 -0.7366) (xy 0.16256 -0.76835) (xy 0.1524 -0.8001)
						(xy 0.13716 -0.82804) (xy 0.11684 -0.85344) (xy 0.09144 -0.87376) (xy 0.0635 -0.889) (xy 0.03175 -0.89916)
					)
					(width 0)
					(fill yes)
				)
			)
		)
		(pad "165" smd custom
			(at 19.949922 -4.100068)
			(size 0.1143 0.1143)
			(layers "B.Cu" "B.Mask" "B.Paste")
			(net "M_A_DQ48")
			(options
				(clearance outline)
				(anchor circle)
			)
			(primitives
				(gr_poly
					(pts
						(xy 0 -0.9017) (xy -0.03175 -0.89916) (xy -0.0635 -0.889) (xy -0.09144 -0.87376) (xy -0.11684 -0.85344)
						(xy -0.13716 -0.82804) (xy -0.1524 -0.8001) (xy -0.16256 -0.76835) (xy -0.1651 -0.7366) (xy -0.1651 -0.44958)
						(xy -0.17272 -0.44196) (xy -0.19812 -0.4064) (xy -0.2032 -0.39624) (xy -0.20701 -0.38735) (xy -0.21209 -0.37719)
						(xy -0.2159 -0.36703) (xy -0.21844 -0.35687) (xy -0.22225 -0.34544) (xy -0.22352 -0.33528) (xy -0.22606 -0.32512)
						(xy -0.22733 -0.31369) (xy -0.22733 -0.30353) (xy -0.2286 -0.2921) (xy -0.22733 -0.28067) (xy -0.22733 -0.27051)
						(xy -0.22606 -0.25908) (xy -0.22352 -0.24892) (xy -0.22225 -0.23876) (xy -0.21844 -0.22733) (xy -0.2159 -0.21717)
						(xy -0.21209 -0.20701) (xy -0.20701 -0.19685) (xy -0.2032 -0.18796) (xy -0.19812 -0.1778) (xy -0.17272 -0.14224)
						(xy -0.1651 -0.13462) (xy -0.1651 0.7366) (xy -0.16256 0.76835) (xy -0.1524 0.8001) (xy -0.13716 0.82804)
						(xy -0.11684 0.85344) (xy -0.09144 0.87376) (xy -0.0635 0.889) (xy -0.03175 0.89916) (xy 0 0.9017)
						(xy 0.03175 0.89916) (xy 0.0635 0.889) (xy 0.09144 0.87376) (xy 0.11684 0.85344) (xy 0.13716 0.82804)
						(xy 0.1524 0.8001) (xy 0.16256 0.76835) (xy 0.1651 0.7366) (xy 0.1651 -0.13462) (xy 0.17272 -0.14224)
						(xy 0.19812 -0.1778) (xy 0.2032 -0.18796) (xy 0.20701 -0.19685) (xy 0.21209 -0.20701) (xy 0.2159 -0.21717)
						(xy 0.21844 -0.22733) (xy 0.22225 -0.23876) (xy 0.22352 -0.24892) (xy 0.22606 -0.25908) (xy 0.22733 -0.27051)
						(xy 0.22733 -0.28067) (xy 0.2286 -0.2921) (xy 0.22733 -0.30353) (xy 0.22733 -0.31369) (xy 0.22606 -0.32512)
						(xy 0.22352 -0.33528) (xy 0.22225 -0.34544) (xy 0.21844 -0.35687) (xy 0.2159 -0.36703) (xy 0.21209 -0.37719)
						(xy 0.20701 -0.38735) (xy 0.2032 -0.39624) (xy 0.19812 -0.4064) (xy 0.17272 -0.44196) (xy 0.1651 -0.44958)
						(xy 0.1651 -0.7366) (xy 0.16256 -0.76835) (xy 0.1524 -0.8001) (xy 0.13716 -0.82804) (xy 0.11684 -0.85344)
						(xy 0.09144 -0.87376) (xy 0.0635 -0.889) (xy 0.03175 -0.89916)
					)
					(width 0)
					(fill yes)
				)
			)
		)
		(pad "166" smd custom
			(at 20.249896 4.100068)
			(size 0.1143 0.1143)
			(layers "B.Cu" "B.Mask" "B.Paste")
			(net "M_A_DQ52")
			(options
				(clearance outline)
				(anchor circle)
			)
			(primitives
				(gr_poly
					(pts
						(xy 0 -0.9017) (xy -0.03175 -0.89916) (xy -0.0635 -0.889) (xy -0.09144 -0.87376) (xy -0.11684 -0.85344)
						(xy -0.13716 -0.82804) (xy -0.1524 -0.8001) (xy -0.16256 -0.76835) (xy -0.1651 -0.7366) (xy -0.1651 0.13462)
						(xy -0.17272 0.14224) (xy -0.19812 0.1778) (xy -0.2032 0.18796) (xy -0.20701 0.19685) (xy -0.21209 0.20701)
						(xy -0.2159 0.21717) (xy -0.21844 0.22733) (xy -0.22225 0.23876) (xy -0.22352 0.24892) (xy -0.22606 0.25908)
						(xy -0.22733 0.27051) (xy -0.22733 0.28067) (xy -0.2286 0.2921) (xy -0.22733 0.30353) (xy -0.22733 0.31369)
						(xy -0.22606 0.32512) (xy -0.22352 0.33528) (xy -0.22225 0.34544) (xy -0.21844 0.35687) (xy -0.2159 0.36703)
						(xy -0.21209 0.37719) (xy -0.20701 0.38735) (xy -0.2032 0.39624) (xy -0.19812 0.4064) (xy -0.17272 0.44196)
						(xy -0.1651 0.44958) (xy -0.1651 0.7366) (xy -0.16256 0.76835) (xy -0.1524 0.8001) (xy -0.13716 0.82804)
						(xy -0.11684 0.85344) (xy -0.09144 0.87376) (xy -0.0635 0.889) (xy -0.03175 0.89916) (xy 0 0.9017)
						(xy 0.03175 0.89916) (xy 0.0635 0.889) (xy 0.09144 0.87376) (xy 0.11684 0.85344) (xy 0.13716 0.82804)
						(xy 0.1524 0.8001) (xy 0.16256 0.76835) (xy 0.1651 0.7366) (xy 0.1651 0.44958) (xy 0.17272 0.44196)
						(xy 0.19812 0.4064) (xy 0.2032 0.39624) (xy 0.20701 0.38735) (xy 0.21209 0.37719) (xy 0.2159 0.36703)
						(xy 0.21844 0.35687) (xy 0.22225 0.34544) (xy 0.22352 0.33528) (xy 0.22606 0.32512) (xy 0.22733 0.31369)
						(xy 0.22733 0.30353) (xy 0.2286 0.2921) (xy 0.22733 0.28067) (xy 0.22733 0.27051) (xy 0.22606 0.25908)
						(xy 0.22352 0.24892) (xy 0.22225 0.23876) (xy 0.21844 0.22733) (xy 0.2159 0.21717) (xy 0.21209 0.20701)
						(xy 0.20701 0.19685) (xy 0.2032 0.18796) (xy 0.19812 0.1778) (xy 0.17272 0.14224) (xy 0.1651 0.13462)
						(xy 0.1651 -0.7366) (xy 0.16256 -0.76835) (xy 0.1524 -0.8001) (xy 0.13716 -0.82804) (xy 0.11684 -0.85344)
						(xy 0.09144 -0.87376) (xy 0.0635 -0.889) (xy 0.03175 -0.89916)
					)
					(width 0)
					(fill yes)
				)
			)
		)
		(pad "167" smd custom
			(at 20.550124 -4.100068)
			(size 0.1143 0.1143)
			(layers "B.Cu" "B.Mask" "B.Paste")
			(net "M_A_DQ49")
			(options
				(clearance outline)
				(anchor circle)
			)
			(primitives
				(gr_poly
					(pts
						(xy 0 -0.9017) (xy -0.03175 -0.89916) (xy -0.0635 -0.889) (xy -0.09144 -0.87376) (xy -0.11684 -0.85344)
						(xy -0.13716 -0.82804) (xy -0.1524 -0.8001) (xy -0.16256 -0.76835) (xy -0.1651 -0.7366) (xy -0.1651 -0.19685)
						(xy -0.17272 -0.18923) (xy -0.17907 -0.18034) (xy -0.18669 -0.17145) (xy -0.19177 -0.16256) (xy -0.19812 -0.15367)
						(xy -0.20828 -0.13335) (xy -0.21971 -0.10287) (xy -0.22225 -0.09271) (xy -0.22479 -0.08128) (xy -0.22606 -0.07112)
						(xy -0.2286 -0.05969) (xy -0.2286 -0.01651) (xy -0.22606 -0.00508) (xy -0.22479 0.00508) (xy -0.22225 0.01651)
						(xy -0.21971 0.02667) (xy -0.20828 0.05715) (xy -0.19812 0.07747) (xy -0.19177 0.08636) (xy -0.18669 0.09525)
						(xy -0.17907 0.10414) (xy -0.17272 0.11303) (xy -0.1651 0.12065) (xy -0.1651 0.7366) (xy -0.16256 0.76835)
						(xy -0.1524 0.8001) (xy -0.13716 0.82804) (xy -0.11684 0.85344) (xy -0.09144 0.87376) (xy -0.0635 0.889)
						(xy -0.03175 0.89916) (xy 0 0.9017) (xy 0.03175 0.89916) (xy 0.0635 0.889) (xy 0.09144 0.87376)
						(xy 0.11684 0.85344) (xy 0.13716 0.82804) (xy 0.1524 0.8001) (xy 0.16256 0.76835) (xy 0.1651 0.7366)
						(xy 0.1651 0.11938) (xy 0.17272 0.11176) (xy 0.19812 0.0762) (xy 0.2032 0.06604) (xy 0.20701 0.05715)
						(xy 0.21209 0.04699) (xy 0.2159 0.03683) (xy 0.21844 0.02667) (xy 0.22225 0.01524) (xy 0.22352 0.00508)
						(xy 0.22606 -0.00508) (xy 0.22733 -0.01651) (xy 0.22733 -0.02667) (xy 0.2286 -0.0381) (xy 0.22733 -0.04953)
						(xy 0.22733 -0.05969) (xy 0.22606 -0.07112) (xy 0.22352 -0.08128) (xy 0.22225 -0.09144) (xy 0.21844 -0.10287)
						(xy 0.2159 -0.11303) (xy 0.21209 -0.12319) (xy 0.20701 -0.13335) (xy 0.2032 -0.14224) (xy 0.19812 -0.1524)
						(xy 0.17272 -0.18796) (xy 0.1651 -0.19558) (xy 0.1651 -0.7366) (xy 0.16256 -0.76835) (xy 0.1524 -0.8001)
						(xy 0.13716 -0.82804) (xy 0.11684 -0.85344) (xy 0.09144 -0.87376) (xy 0.0635 -0.889) (xy 0.03175 -0.89916)
					)
					(width 0)
					(fill yes)
				)
			)
		)
	)
)
